# S9S_MB_2U (Grand Teton) — schematic netlist excerpt (pin names and nets, part order shuffled) for the footprints in the layout excerpt that follows; sources: Cadence DE-HDL packaged netlist, KiCad conversion of 03242023_DA0F0TMBIJ0_F0T_Motherboard_J_brd_V01_OCP.brd

R851  Q_RES  0 5% CHIP  pkg 0402LF  page 128 : A = RST_CPU0_DRAM_AB_N ; B = RST_CPU0_DRAM_AB_PLD_N
C2338  Q_CAP  0.1UF 25V 10% X7R  pkg 0402  page 237 : A = P3V3 ; B = GND

(kicad_pcb
	(version 20260206)
	(generator "pcbnew")
	(generator_version "10.0")
	(general
		(thickness 1.6)
		(legacy_teardrops no)
	)
	(paper "A4")
	(title_block
		(title "03242023_DA0F0TMBIJ0_F0T_Motherboard_J_brd_V01_OCP.brd")
		(comment 1 "Grand Teton / footprints 2738-2739 of 6105")
	)
	(layers
		(0 "F.Cu" signal "TOP")
		(4 "In1.Cu" signal "GND")
		(6 "In2.Cu" signal "IN1")
		(8 "In3.Cu" signal "GND1")
		(10 "In4.Cu" signal "IN2")
		(12 "In5.Cu" signal "GND2")
		(14 "In6.Cu" signal "IN3")
		(16 "In7.Cu" signal "GND3")
		(18 "In8.Cu" signal "VCC")
		(20 "In9.Cu" signal "VCC1")
		(22 "In10.Cu" signal "GND4")
		(24 "In11.Cu" signal "IN4")
		(26 "In12.Cu" signal "GND5")
		(28 "In13.Cu" signal "IN5")
		(30 "In14.Cu" signal "GND6")
		(32 "In15.Cu" signal "IN6")
		(34 "In16.Cu" signal "GND7")
		(2 "B.Cu" signal "BOTTOM")
		(9 "F.Adhes" user "F.Adhesive")
		(11 "B.Adhes" user "B.Adhesive")
		(13 "F.Paste" user "Package Geometry/Pastemask Top")
		(15 "B.Paste" user "Package Geometry/Pastemask Bottom")
		(5 "F.SilkS" user "Ref Des/Silkscreen Top")
		(7 "B.SilkS" user "Ref Des/Silkscreen Bottom")
		(1 "F.Mask" user "Board Geometry/Soldermask Top")
		(3 "B.Mask" user "Board Geometry/Soldermask Bottom")
		(17 "Dwgs.User" user "User.Drawings")
		(19 "Cmts.User" user "User.Comments")
		(21 "Eco1.User" user "User.Eco1")
		(23 "Eco2.User" user "User.Eco2")
		(25 "Edge.Cuts" user "Board Geometry/Outline")
		(27 "Margin" user)
		(31 "F.CrtYd" user "Package Geometry/Place Bound Top")
		(29 "B.CrtYd" user "Package Geometry/Place Bound Bottom")
		(35 "F.Fab" user "Ref Des/Assembly Top")
		(33 "B.Fab" user "Ref Des/Assembly Bottom")
	)
	(footprint ""
		(layer "F.Cu")
		(at 264.126726 -129.439924 180)
		(property "Reference" "C2338"
			(at 0 0 180)
			(layer "F.SilkS")
			(hide yes)
			(effects
				(font
					(size 1.27 1.27)
				)
			)
		)
		(property "Value" ""
			(at 0 0 180)
			(layer "F.Fab")
			(effects
				(font
					(size 1.27 1.27)
				)
			)
		)
		(duplicate_pad_numbers_are_jumpers no)
		(fp_line
			(start 0.7874 0.4064)
			(end -0.7874 0.4064)
			(stroke
				(width 0.1524)
				(type default)
			)
			(layer "F.SilkS")
		)
		(fp_line
			(start 0.7874 -0.4064)
			(end 0.7874 0.4064)
			(stroke
				(width 0.1524)
				(type default)
			)
			(layer "F.SilkS")
		)
		(fp_line
			(start -0.7874 0.4064)
			(end -0.7874 -0.4064)
			(stroke
				(width 0.1524)
				(type default)
			)
			(layer "F.SilkS")
		)
		(fp_line
			(start -0.7874 -0.4064)
			(end 0.7874 -0.4064)
			(stroke
				(width 0.1524)
				(type default)
			)
			(layer "F.SilkS")
		)
		(fp_line
			(start 0.67945 0.3048)
			(end 0.120396 0.3048)
			(stroke
				(width 0.1)
				(type default)
			)
			(layer "F.Fab")
		)
		(fp_line
			(start 0.67945 -0.3048)
			(end 0.67945 0.3048)
			(stroke
				(width 0.1)
				(type default)
			)
			(layer "F.Fab")
		)
		(fp_line
			(start 0.12065 -0.2794)
			(end 0.12065 -0.3048)
			(stroke
				(width 0.1)
				(type default)
			)
			(layer "F.Fab")
		)
		(fp_line
			(start 0.12065 -0.3048)
			(end 0.67945 -0.3048)
			(stroke
				(width 0.1)
				(type default)
			)
			(layer "F.Fab")
		)
		(fp_line
			(start 0.120396 0.3048)
			(end 0.120396 0.2794)
			(stroke
				(width 0.1)
				(type default)
			)
			(layer "F.Fab")
		)
		(fp_line
			(start 0.120396 0.2794)
			(end -0.12065 0.2794)
			(stroke
				(width 0.1)
				(type default)
			)
			(layer "F.Fab")
		)
		(fp_line
			(start -0.12065 0.3048)
			(end -0.67945 0.3048)
			(stroke
				(width 0.1)
				(type default)
			)
			(layer "F.Fab")
		)
		(fp_line
			(start -0.12065 0.2794)
			(end -0.12065 0.3048)
			(stroke
				(width 0.1)
				(type default)
			)
			(layer "F.Fab")
		)
		(fp_line
			(start -0.12065 -0.2794)
			(end 0.12065 -0.2794)
			(stroke
				(width 0.1)
				(type default)
			)
			(layer "F.Fab")
		)
		(fp_line
			(start -0.12065 -0.305054)
			(end -0.12065 -0.2794)
			(stroke
				(width 0.1)
				(type default)
			)
			(layer "F.Fab")
		)
		(fp_line
			(start -0.67945 0.3048)
			(end -0.67945 -0.305054)
			(stroke
				(width 0.1)
				(type default)
			)
			(layer "F.Fab")
		)
		(fp_line
			(start -0.67945 -0.305054)
			(end -0.12065 -0.305054)
			(stroke
				(width 0.1)
				(type default)
			)
			(layer "F.Fab")
		)
		(pad "1" smd circle
			(at -0.40005 0 180)
			(size 0 0)
			(layers "F.Cu" "F.Mask" "F.Paste")
			(net "P3V3")
		)
		(pad "2" smd circle
			(at 0.40005 0 180)
			(size 0 0)
			(layers "F.Cu" "F.Mask" "F.Paste")
			(net "GND")
		)
	)
	(footprint ""
		(layer "F.Cu")
		(at 111.13008 -119.846598 -90)
		(property "Reference" "R851"
			(at 0 0 270)
			(layer "F.SilkS")
			(hide yes)
			(effects
				(font
					(size 1.27 1.27)
				)
			)
		)
		(property "Value" ""
			(at 0 0 270)
			(layer "F.Fab")
			(effects
				(font
					(size 1.27 1.27)
				)
			)
		)
		(duplicate_pad_numbers_are_jumpers no)
		(fp_line
			(start -0.7874 0.4064)
			(end -0.7874 -0.4064)
			(stroke
				(width 0.1524)
				(type default)
			)
			(layer "F.SilkS")
		)
		(fp_line
			(start 0.7874 0.4064)
			(end -0.7874 0.4064)
			(stroke
				(width 0.1524)
				(type default)
			)
			(layer "F.SilkS")
		)
		(fp_line
			(start -0.7874 -0.4064)
			(end 0.7874 -0.4064)
			(stroke
				(width 0.1524)
				(type default)
			)
			(layer "F.SilkS")
		)
		(fp_line
			(start 0.7874 -0.4064)
			(end 0.7874 0.4064)
			(stroke
				(width 0.1524)
				(type default)
			)
			(layer "F.SilkS")
		)
		(fp_line
			(start -0.67945 0.3048)
			(end -0.67945 -0.305054)
			(stroke
				(width 0.1)
				(type default)
			)
			(layer "F.Fab")
		)
		(fp_line
			(start -0.12065 0.3048)
			(end -0.67945 0.3048)
			(stroke
				(width 0.1)
				(type default)
			)
			(layer "F.Fab")
		)
		(fp_line
			(start 0.120396 0.3048)
			(end 0.120396 0.2794)
			(stroke
				(width 0.1)
				(type default)
			)
			(layer "F.Fab")
		)
		(fp_line
			(start 0.67945 0.3048)
			(end 0.120396 0.3048)
			(stroke
				(width 0.1)
				(type default)
			)
			(layer "F.Fab")
		)
		(fp_line
			(start -0.12065 0.2794)
			(end -0.12065 0.3048)
			(stroke
				(width 0.1)
				(type default)
			)
			(layer "F.Fab")
		)
		(fp_line
			(start 0.120396 0.2794)
			(end -0.12065 0.2794)
			(stroke
				(width 0.1)
				(type default)
			)
			(layer "F.Fab")
		)
		(fp_line
			(start -0.12065 -0.2794)
			(end 0.12065 -0.2794)
			(stroke
				(width 0.1)
				(type default)
			)
			(layer "F.Fab")
		)
		(fp_line
			(start 0.12065 -0.2794)
			(end 0.12065 -0.3048)
			(stroke
				(width 0.1)
				(type default)
			)
			(layer "F.Fab")
		)
		(fp_line
			(start 0.12065 -0.3048)
			(end 0.67945 -0.3048)
			(stroke
				(width 0.1)
				(type default)
			)
			(layer "F.Fab")
		)
		(fp_line
			(start 0.67945 -0.3048)
			(end 0.67945 0.3048)
			(stroke
				(width 0.1)
				(type default)
			)
			(layer "F.Fab")
		)
		(fp_line
			(start -0.67945 -0.305054)
			(end -0.12065 -0.305054)
			(stroke
				(width 0.1)
				(type default)
			)
			(layer "F.Fab")
		)
		(fp_line
			(start -0.12065 -0.305054)
			(end -0.12065 -0.2794)
			(stroke
				(width 0.1)
				(type default)
			)
			(layer "F.Fab")
		)
		(pad "1" smd circle
			(at -0.40005 0 270)
			(size 0 0)
			(layers "F.Cu" "F.Mask" "F.Paste")
			(net "RST_CPU0_DRAM_AB_N")
		)
		(pad "2" smd circle
			(at 0.40005 0 270)
			(size 0 0)
			(layers "F.Cu" "F.Mask" "F.Paste")
			(net "RST_CPU0_DRAM_AB_PLD_N")
		)
	)
)
